P  UNITS CUST 0
C   
C   vSure IPC 356 OUTPUT.  
C
C   FTP Site : valor.com
C   WEB Site : http://www.valor.com 
C
P   NNAME00000     CLK_100M_PCIE_SAS_C_P                                    
P   NNAME00001     CLK_100M_PCIE_SAS_C_N                                    
P   NNAME00002     P2E_CPU_SAS_RX_DP0                                       
P   NNAME00003     P2E_CPU_SAS_RX_DN0                                       
P   NNAME00004     P2E_CPU_SAS_RX_DP1                                       
P   NNAME00005     P2E_CPU_SAS_RX_DN1                                       
P   NNAME00006     P2E_CPU_SAS_RX_DP2                                       
P   NNAME00007     P2E_CPU_SAS_RX_DN2                                       
P   NNAME00008     P2E_CPU_SAS_RX_DP3                                       
P   NNAME00009     P2E_CPU_SAS_RX_DN3                                       
P   NNAME00010     CPU_GBE_RX_C_DP0                                         
P   NNAME00011     CPU_GBE_RX_C_DN0                                         
P   NNAME00012     P2E_CPU_SAS_RX_DP4                                       
P   NNAME00013     P2E_CPU_SAS_RX_DN4                                       
P   NNAME00014     P2E_CPU_SAS_RX_DP5                                       
P   NNAME00015     P2E_CPU_SAS_RX_DN5                                       
P   NNAME00016     P2E_CPU_SAS_RX_DP6                                       
P   NNAME00017     P2E_CPU_SAS_RX_DN6                                       
P   NNAME00018     P2E_CPU_SAS_RX_DP7                                       
P   NNAME00019     P2E_CPU_SAS_RX_DN7                                       
P   NNAME00020     P2E_CPU_ETH10G_RX_DP8                                    
P   NNAME00021     P2E_CPU_ETH10G_RX_DN8                                    
P   NNAME00022     P2E_CPU_ETH10G_RX_DP9                                    
P   NNAME00023     P2E_CPU_ETH10G_RX_DN9                                    
P   NNAME00024     P2E_CPU_ETH10G_RX_DP10                                   
P   NNAME00025     P2E_CPU_ETH10G_RX_DN10                                   
P   NNAME00026     P2E_CPU_ETH10G_RX_DP11                                   
P   NNAME00027     P2E_CPU_ETH10G_RX_DN11                                   
P   NNAME00028     P2E_CPU_SAS_TX_DP0                                       
P   NNAME00029     P2E_CPU_SAS_TX_DN0                                       
P   NNAME00030     P2E_CPU_SAS_TX_DP1                                       
P   NNAME00031     P2E_CPU_SAS_TX_DN1                                       
P   NNAME00032     P2E_CPU_SAS_TX_DP2                                       
P   NNAME00033     P2E_CPU_SAS_TX_DN2                                       
P   NNAME00034     P2E_CPU_SAS_TX_DP3                                       
P   NNAME00035     P2E_CPU_SAS_TX_DN3                                       
P   NNAME00036     CLK_100M_CLKBUFF_ENET_DP                                 
P   NNAME00037     CLK_100M_CLKBUFF_ENET_DN                                 
P   NNAME00038     CPU_GBE_TX_C_DP0                                         
P   NNAME00039     CPU_GBE_TX_C_DN0                                         
P   NNAME00040     P2E_CPU_SAS_TX_DP4                                       
P   NNAME00041     P2E_CPU_SAS_TX_DN4                                       
P   NNAME00042     P2E_CPU_SAS_TX_DP5                                       
P   NNAME00043     P2E_CPU_SAS_TX_DN5                                       
P   NNAME00044     P2E_CPU_SAS_TX_DP6                                       
P   NNAME00045     P2E_CPU_SAS_TX_DN6                                       
P   NNAME00046     P2E_CPU_SAS_TX_DP7                                       
P   NNAME00047     P2E_CPU_SAS_TX_DN7                                       
P   NNAME00048     P2E_CPU_ETH10G_TX_DP8                                    
P   NNAME00049     P2E_CPU_ETH10G_TX_DN8                                    
P   NNAME00050     P2E_CPU_ETH10G_TX_DP9                                    
P   NNAME00051     P2E_CPU_ETH10G_TX_DN9                                    
P   NNAME00052     P2E_CPU_ETH10G_TX_DP10                                   
P   NNAME00053     P2E_CPU_ETH10G_TX_DN10                                   
P   NNAME00054     P2E_CPU_ETH10G_TX_DP11                                   
P   NNAME00055     P2E_CPU_ETH10G_TX_DN11                                   
327BOARD_PRSNT#                 D0040PA01X+035039Y+001571               S0      
317BOARD_PRSNT#                 D0040PA00X+035039Y+007343               S0      
327P12V                         D0040PA01X+034646Y+001376               S0      
327P12V                         D0040PA01X+034252Y+001376               S0      
327P12V                         D0040PA01X+002756Y+001376               S0      
327P12V                         D0040PA01X+002362Y+001376               S0      
327P12V                         D0040PA04X+035039Y+001376               S0      
327P12V                         D0040PA04X+034646Y+001376               S0      
327P12V                         D0040PA04X+034252Y+001376               S0      
317P12V                         D0040PA00X+034646Y+006555               S0      
317P12V                         D0040PA00X+034252Y+007343               S0      
317P12V                         D0040PA00X+002756Y+007343               S0      
317P12V                         D0040PA00X+002362Y+006555               S0      
317P12V                         D0040PA00X+035039Y+008327               S0      
317P12V                         D0040PA00X+034646Y+009114               S0      
317P12V                         D0040PA00X+034252Y+008327               S0      
317P12V             VIA        MD0040PA00X+001533Y+006270               S0      
317P12V             VIA        MD0040PA00X+001563Y+006950               S0      
317P12V             VIA        MD0040PA00X+001703Y+005345               S0      
317P12V             VIA        MD0040PA00X+002153Y+005910               S0      
317P12V             VIA        MD0040PA00X+002372Y+003788               S0      
317P12V             VIA        MD0040PA00X+002573Y+005345               S0      
317P12V             VIA        MD0040PA00X+003068Y+004270               S0      
317P12V             VIA        MD0040PA00X+003083Y+005870               S0      
317P12V             VIA        MD0040PA00X+034001Y+005857               S0      
317P12V             VIA        MD0040PA00X+034008Y+004796               S0      
317P12V             VIA        MD0040PA00X+034302Y+003250               S0      
317P12V             VIA        MD0040PA00X+034370Y+005389               S0      
317P12V             VIA        MD0040PA00X+034436Y+004367               S0      
317P12V             VIA        MD0040PA00X+034754Y+003240               S0      
317P12V             VIA        MD0040PA00X+035465Y+008989               S0      
317P12V             VIA        MD0040PA00X+035577Y+007868               S0      
317P12V             VIA        MD0040PA00X+035735Y+007216               S0      
327GND                          D0040PA01X+033858Y+001376               S0      
327GND                          D0040PA01X+029921Y+001376               S0      
327GND                          D0040PA01X+028740Y+001376               S0      
327GND                          D0040PA01X+028346Y+001376               S0      
327GND                          D0040PA01X+027165Y+001376               S0      
327GND                          D0040PA01X+026772Y+001376               S0      
327GND                          D0040PA01X+025591Y+001376               S0      
327GND                          D0040PA01X+025197Y+001376               S0      
327GND                          D0040PA01X+024016Y+001376               S0      
327GND                          D0040PA01X+023622Y+001376               S0      
327GND                          D0040PA01X+022441Y+001376               S0      
327GND                          D0040PA01X+022047Y+001376               S0      
327GND                          D0040PA01X+020866Y+001376               S0      
327GND                          D0040PA01X+020472Y+001376               S0      
327GND                          D0040PA01X+019291Y+001376               S0      
327GND                          D0040PA01X+018898Y+001376               S0      
327GND                          D0040PA01X+017717Y+001376               S0      
327GND                          D0040PA01X+017323Y+001376               S0      
327GND                          D0040PA01X+016142Y+001376               S0      
327GND                          D0040PA01X+015748Y+001376               S0      
327GND                          D0040PA01X+014567Y+001376               S0      
327GND                          D0040PA01X+014173Y+001376               S0      
327GND                          D0040PA01X+012992Y+001376               S0      
327GND                          D0040PA01X+012598Y+001376               S0      
327GND                          D0040PA01X+011417Y+001376               S0      
327GND                          D0040PA01X+011024Y+001376               S0      
327GND                          D0040PA01X+009843Y+001376               S0      
327GND                          D0040PA01X+009449Y+001376               S0      
327GND                          D0040PA01X+008268Y+001376               S0      
327GND                          D0040PA01X+007874Y+001376               S0      
327GND                          D0040PA01X+006693Y+001376               S0      
327GND                          D0040PA01X+006299Y+001376               S0      
327GND                          D0040PA01X+005118Y+001376               S0      
327GND                          D0040PA01X+004724Y+001376               S0      
327GND                          D0040PA01X+003543Y+001376               S0      
327GND                          D0040PA01X+003150Y+001376               S0      
327GND                          D0040PA04X+033858Y+001376               S0      
327GND                          D0040PA04X+032677Y+001376               S0      
327GND                          D0040PA04X+029528Y+001376               S0      
327GND                          D0040PA04X+029134Y+001376               S0      
327GND                          D0040PA04X+027953Y+001571               S0      
327GND                          D0040PA04X+027559Y+001376               S0      
327GND                          D0040PA04X+026378Y+001376               S0      
327GND                          D0040PA04X+025984Y+001376               S0      
327GND                          D0040PA04X+024803Y+001376               S0      
327GND                          D0040PA04X+024409Y+001376               S0      
327GND                          D0040PA04X+023228Y+001376               S0      
327GND                          D0040PA04X+022835Y+001376               S0      
327GND                          D0040PA04X+021653Y+001376               S0      
327GND                          D0040PA04X+021260Y+001376               S0      
327GND                          D0040PA04X+020079Y+001376               S0      
327GND                          D0040PA04X+019685Y+001376               S0      
327GND                          D0040PA04X+018504Y+001376               S0      
327GND                          D0040PA04X+018110Y+001376               S0      
327GND                          D0040PA04X+016929Y+001376               S0      
327GND                          D0040PA04X+016535Y+001376               S0      
327GND                          D0040PA04X+015354Y+001376               S0      
327GND                          D0040PA04X+014961Y+001376               S0      
327GND                          D0040PA04X+013780Y+001376               S0      
327GND                          D0040PA04X+013386Y+001376               S0      
327GND                          D0040PA04X+012205Y+001376               S0      
327GND                          D0040PA04X+011811Y+001376               S0      
327GND                          D0040PA04X+010630Y+001376               S0      
327GND                          D0040PA04X+010236Y+001376               S0      
327GND                          D0040PA04X+009055Y+001376               S0      
327GND                          D0040PA04X+008661Y+001376               S0      
327GND                          D0040PA04X+007480Y+001376               S0      
327GND                          D0040PA04X+007087Y+001376               S0      
327GND                          D0040PA04X+005906Y+001376               S0      
327GND                          D0040PA04X+005512Y+001376               S0      
327GND                          D0040PA04X+004331Y+001376               S0      
327GND                          D0040PA04X+003937Y+001376               S0      
327GND                          D0040PA04X+002756Y+001571               S0      
327GND                          D0040PA04X+002362Y+001376               S0      
317GND                          D0040PA00X+033858Y+006555               S0      
317GND                          D0040PA00X+029921Y+006555               S0      
317GND                          D0040PA00X+028740Y+007343               S0      
317GND                          D0040PA00X+028346Y+006555               S0      
317GND                          D0040PA00X+027165Y+007343               S0      
317GND                          D0040PA00X+026772Y+006555               S0      
317GND                          D0040PA00X+025591Y+007343               S0      
317GND                          D0040PA00X+025197Y+006555               S0      
317GND                          D0040PA00X+024016Y+007343               S0      
317GND                          D0040PA00X+023622Y+006555               S0      
317GND                          D0040PA00X+022441Y+007343               S0      
317GND                          D0040PA00X+022047Y+006555               S0      
317GND                          D0040PA00X+020866Y+007343               S0      
317GND                          D0040PA00X+020472Y+006555               S0      
317GND                          D0040PA00X+019291Y+007343               S0      
317GND                          D0040PA00X+018898Y+006555               S0      
317GND                          D0040PA00X+017717Y+007343               S0      
317GND                          D0040PA00X+017323Y+006555               S0      
317GND                          D0040PA00X+016142Y+007343               S0      
317GND                          D0040PA00X+015748Y+006555               S0      
317GND                          D0040PA00X+014567Y+007343               S0      
317GND                          D0040PA00X+014173Y+006555               S0      
317GND                          D0040PA00X+012992Y+007343               S0      
317GND                          D0040PA00X+012598Y+006555               S0      
317GND                          D0040PA00X+011417Y+007343               S0      
317GND                          D0040PA00X+011024Y+006555               S0      
317GND                          D0040PA00X+009843Y+007343               S0      
317GND                          D0040PA00X+009449Y+006555               S0      
317GND                          D0040PA00X+008268Y+007343               S0      
317GND                          D0040PA00X+007874Y+006555               S0      
317GND                          D0040PA00X+006693Y+007343               S0      
317GND                          D0040PA00X+006299Y+006555               S0      
317GND                          D0040PA00X+005118Y+007343               S0      
317GND                          D0040PA00X+004724Y+006555               S0      
317GND                          D0040PA00X+003543Y+007343               S0      
317GND                          D0040PA00X+003150Y+006555               S0      
317GND                          D0040PA00X+033858Y+009114               S0      
317GND                          D0040PA00X+032677Y+008327               S0      
317GND                          D0040PA00X+029528Y+008327               S0      
317GND                          D0040PA00X+029134Y+009114               S0      
317GND                          D0040PA00X+027953Y+008327               S0      
317GND                          D0040PA00X+027559Y+009114               S0      
317GND                          D0040PA00X+026378Y+008327               S0      
317GND                          D0040PA00X+025984Y+009114               S0      
317GND                          D0040PA00X+024803Y+008327               S0      
317GND                          D0040PA00X+024409Y+009114               S0      
317GND                          D0040PA00X+023228Y+008327               S0      
317GND                          D0040PA00X+022835Y+009114               S0      
317GND                          D0040PA00X+021654Y+008327               S0      
317GND                          D0040PA00X+021260Y+009114               S0      
317GND                          D0040PA00X+020079Y+008327               S0      
317GND                          D0040PA00X+019685Y+009114               S0      
317GND                          D0040PA00X+018504Y+008327               S0      
317GND                          D0040PA00X+018110Y+009114               S0      
317GND                          D0040PA00X+016929Y+008327               S0      
317GND                          D0040PA00X+016535Y+009114               S0      
317GND                          D0040PA00X+015354Y+008327               S0      
317GND                          D0040PA00X+014961Y+009114               S0      
317GND                          D0040PA00X+013780Y+008327               S0      
317GND                          D0040PA00X+013386Y+009114               S0      
317GND                          D0040PA00X+012205Y+008327               S0      
317GND                          D0040PA00X+011811Y+009114               S0      
317GND                          D0040PA00X+010630Y+008327               S0      
317GND                          D0040PA00X+010236Y+009114               S0      
317GND                          D0040PA00X+009055Y+008327               S0      
317GND                          D0040PA00X+008661Y+009114               S0      
317GND                          D0040PA00X+007480Y+008327               S0      
317GND                          D0040PA00X+007087Y+009114               S0      
317GND                          D0040PA00X+005906Y+008327               S0      
317GND                          D0040PA00X+005512Y+009114               S0      
317GND                          D0040PA00X+004331Y+008327               S0      
317GND                          D0040PA00X+003937Y+009114               S0      
317GND                          D0040PA00X+002756Y+008327               S0      
317GND                          D0040PA00X+002362Y+009114               S0      
317GND              VIA        MD0040PA00X+010073Y+003150               S0      
317GND              VIA        MD0040PA00X+010833Y+003160               S0      
317GND              VIA        MD0040PA00X+011623Y+003150               S0      
317GND              VIA        MD0040PA00X+012423Y+003160               S0      
317GND              VIA        MD0040PA00X+013233Y+003160               S0      
317GND              VIA        MD0040PA00X+013973Y+003150               S0      
317GND              VIA        MD0040PA00X+014783Y+003150               S0      
317GND              VIA        MD0040PA00X+015543Y+003160               S0      
317GND              VIA        MD0040PA00X+016373Y+003150               S0      
317GND              VIA        MD0040PA00X+017133Y+003160               S0      
317GND              VIA        MD0040PA00X+017913Y+003160               S0      
317GND              VIA        MD0040PA00X+018898Y+003154               S0      
317GND              VIA        MD0040PA00X+019493Y+003160               S0      
317GND              VIA        MD0040PA00X+020243Y+003140               S0      
317GND              VIA        MD0040PA00X+021063Y+003150               S0      
317GND              VIA        MD0040PA00X+021903Y+003160               S0      
317GND              VIA        MD0040PA00X+022693Y+003150               S0      
317GND              VIA        MD0040PA00X+023433Y+003140               S0      
317GND              VIA        MD0040PA00X+024233Y+003160               S0      
317GND              VIA        MD0040PA00X+024953Y+003140               S0      
317GND              VIA        MD0040PA00X+025823Y+003130               S0      
317GND              VIA        MD0040PA00X+026603Y+003102               S0      
317GND              VIA        MD0040PA00X+027443Y+003140               S0      
317GND              VIA        MD0040PA00X+028093Y+003140               S0      
317GND              VIA        MD0040PA00X+028853Y+003102               S0      
317GND              VIA        MD0040PA00X+029528Y+003166               S0      
317GND              VIA        MD0040PA00X+032963Y+003110               S0      
317GND              VIA        MD0040PA00X+033858Y+003205               S0      
317GND              VIA        MD0040PA00X+003536Y+003796               S0      
317GND              VIA        MD0040PA00X+003813Y+003150               S0      
317GND              VIA        MD0040PA00X+004563Y+003160               S0      
317GND              VIA        MD0040PA00X+005273Y+003140               S0      
317GND              VIA        MD0040PA00X+006063Y+003150               S0      
317GND              VIA        MD0040PA00X+006863Y+003140               S0      
317GND              VIA        MD0040PA00X+007723Y+003170               S0      
317GND              VIA        MD0040PA00X+008423Y+003140               S0      
317GND              VIA        MD0040PA00X+009253Y+003150               S0      
327SLOT_ID0                     D0040PA01X+033465Y+001376               S0      
317SLOT_ID0                     D0040PA00X+033465Y+007343               S0      
327SLOT_ID1                     D0040PA01X+033071Y+001376               S0      
317SLOT_ID1                     D0040PA00X+033071Y+006555               S0      
327CPU_TXD                      D0040PA01X+032677Y+001376               S0      
317CPU_TXD                      D0040PA00X+032677Y+007343               S0      
327CPU_RXD                      D0040PA01X+032284Y+001376               S0      
317CPU_RXD                      D0040PA00X+032283Y+006555               S0      
327SLOT_ID2                     D0040PA01X+031890Y+001376               S0      
317SLOT_ID2                     D0040PA00X+031890Y+007343               S0      
327SLOT_ID3                     D0040PA01X+031496Y+001376               S0      
317SLOT_ID3                     D0040PA00X+031496Y+006555               S0      
327PCIE_RESET#                  D0040PA01X+031102Y+001376               S0      
317PCIE_RESET#                  D0040PA00X+031102Y+007343               S0      
327NNAME00000                   D0040PA01X+029528Y+001376               S0      
317NNAME00000                   D0040PA00X+029528Y+007343               S0      
327NNAME00001                   D0040PA01X+029134Y+001376               S0      
317NNAME00001                   D0040PA00X+029134Y+006555               S0      
327NNAME00002                   D0040PA01X+027953Y+001376               S0      
317NNAME00002                   D0040PA00X+027953Y+007343               S0      
327NNAME00003                   D0040PA01X+027559Y+001376               S0      
317NNAME00003                   D0040PA00X+027559Y+006555               S0      
327NNAME00004                   D0040PA01X+026378Y+001376               S0      
317NNAME00004                   D0040PA00X+026378Y+007343               S0      
327NNAME00005                   D0040PA01X+025984Y+001376               S0      
317NNAME00005                   D0040PA00X+025984Y+006555               S0      
327NNAME00006                   D0040PA01X+024803Y+001376               S0      
317NNAME00006                   D0040PA00X+024803Y+007343               S0      
327NNAME00007                   D0040PA01X+024409Y+001376               S0      
317NNAME00007                   D0040PA00X+024409Y+006555               S0      
327NNAME00008                   D0040PA01X+023228Y+001376               S0      
317NNAME00008                   D0040PA00X+023228Y+007343               S0      
327NNAME00009                   D0040PA01X+022835Y+001376               S0      
317NNAME00009                   D0040PA00X+022835Y+006555               S0      
327SATA2_RX_C_DP0               D0040PA01X+021653Y+001376               S0      
317SATA2_RX_C_DP0               D0040PA00X+021654Y+007343               S0      
327SATA2_RX_C_DN0               D0040PA01X+021260Y+001376               S0      
317SATA2_RX_C_DN0               D0040PA00X+021260Y+006555               S0      
327PCIE_RSVD_A37                D0040PA01X+020079Y+001376               S0      
317PCIE_RSVD_A37                D0040PA00X+020079Y+007343               S0      
327PCIE_RSVD_A38                D0040PA01X+019685Y+001376               S0      
317PCIE_RSVD_A38                D0040PA00X+019685Y+006555               S0      
327PCIE_RSVD_A41                D0040PA01X+018504Y+001376               S0      
317PCIE_RSVD_A41                D0040PA00X+018504Y+007343               S0      
327GBE_SMBALRT_R#               D0040PA01X+018110Y+001376               S0      
317GBE_SMBALRT_R#               D0040PA00X+018110Y+006555               S0      
327NNAME00010                   D0040PA01X+016929Y+001376               S0      
317NNAME00010                   D0040PA00X+016929Y+007343               S0      
327NNAME00011                   D0040PA01X+016535Y+001376               S0      
317NNAME00011                   D0040PA00X+016535Y+006555               S0      
327NNAME00012                   D0040PA01X+015354Y+001376               S0      
317NNAME00012                   D0040PA00X+015354Y+007343               S0      
327NNAME00013                   D0040PA01X+014961Y+001376               S0      
317NNAME00013                   D0040PA00X+014961Y+006555               S0      
327NNAME00014                   D0040PA01X+013780Y+001376               S0      
317NNAME00014                   D0040PA00X+013780Y+007343               S0      
327NNAME00015                   D0040PA01X+013386Y+001376               S0      
317NNAME00015                   D0040PA00X+013386Y+006555               S0      
327NNAME00016                   D0040PA01X+012205Y+001376               S0      
317NNAME00016                   D0040PA00X+012205Y+007343               S0      
327NNAME00017                   D0040PA01X+011811Y+001376               S0      
317NNAME00017                   D0040PA00X+011811Y+006555               S0      
327NNAME00018                   D0040PA01X+010630Y+001376               S0      
317NNAME00018                   D0040PA00X+010630Y+007343               S0      
327NNAME00019                   D0040PA01X+010236Y+001376               S0      
317NNAME00019                   D0040PA00X+010236Y+006555               S0      
327NNAME00020                   D0040PA01X+009055Y+001376               S0      
317NNAME00020                   D0040PA00X+009055Y+007343               S0      
327NNAME00021                   D0040PA01X+008661Y+001376               S0      
317NNAME00021                   D0040PA00X+008661Y+006555               S0      
327NNAME00022                   D0040PA01X+007480Y+001376               S0      
317NNAME00022                   D0040PA00X+007480Y+007343               S0      
327NNAME00023                   D0040PA01X+007087Y+001376               S0      
317NNAME00023                   D0040PA00X+007087Y+006555               S0      
327NNAME00024                   D0040PA01X+005906Y+001376               S0      
317NNAME00024                   D0040PA00X+005906Y+007343               S0      
327NNAME00025                   D0040PA01X+005512Y+001376               S0      
317NNAME00025                   D0040PA00X+005512Y+006555               S0      
327NNAME00026                   D0040PA01X+004331Y+001376               S0      
317NNAME00026                   D0040PA00X+004331Y+007343               S0      
327NNAME00027                   D0040PA01X+003937Y+001376               S0      
317NNAME00027                   D0040PA00X+003937Y+006555               S0      
327BMC_I2C_CLK                  D0040PA04X+033465Y+001376               S0      
317BMC_I2C_CLK                  D0040PA00X+033465Y+008327               S0      
327BMC_I2C_DATA                 D0040PA04X+033071Y+001376               S0      
317BMC_I2C_DATA                 D0040PA00X+033071Y+009114               S0      
327PMU_PWRBTN#                  D0040PA04X+032284Y+001376               S0      
317PMU_PWRBTN#                  D0040PA00X+032283Y+009114               S0      
327USB_P1_DP                    D0040PA04X+031890Y+001376               S0      
317USB_P1_DP                    D0040PA00X+031890Y+008327               S0      
327USB_P1_DN                    D0040PA04X+031496Y+001376               S0      
317USB_P1_DN                    D0040PA00X+031496Y+009114               S0      
327BMC_SYS_RESET#               D0040PA04X+031102Y+001376               S0      
317BMC_SYS_RESET#               D0040PA00X+031102Y+008327               S0      
327BMC_I2C_ALERT#               D0040PA04X+029921Y+001376               S0      
317BMC_I2C_ALERT#               D0040PA00X+029921Y+009114               S0      
327NNAME00028                   D0040PA04X+028740Y+001376               S0      
317NNAME00028                   D0040PA00X+028740Y+008327               S0      
327NNAME00029                   D0040PA04X+028346Y+001376               S0      
317NNAME00029                   D0040PA00X+028346Y+009114               S0      
327NNAME00030                   D0040PA04X+027165Y+001376               S0      
317NNAME00030                   D0040PA00X+027165Y+008327               S0      
327NNAME00031                   D0040PA04X+026772Y+001376               S0      
317NNAME00031                   D0040PA00X+026772Y+009114               S0      
327NNAME00032                   D0040PA04X+025591Y+001376               S0      
317NNAME00032                   D0040PA00X+025591Y+008327               S0      
327NNAME00033                   D0040PA04X+025197Y+001376               S0      
317NNAME00033                   D0040PA00X+025197Y+009114               S0      
327NNAME00034                   D0040PA04X+024016Y+001376               S0      
317NNAME00034                   D0040PA00X+024016Y+008327               S0      
327NNAME00035                   D0040PA04X+023622Y+001376               S0      
317NNAME00035                   D0040PA00X+023622Y+009114               S0      
327SATA2_TX_C_DP0               D0040PA04X+022441Y+001571               S0      
317SATA2_TX_C_DP0               D0040PA00X+022441Y+008327               S0      
327SATA2_TX_C_DN0               D0040PA04X+022047Y+001376               S0      
317SATA2_TX_C_DN0               D0040PA00X+022047Y+009114               S0      
327NNAME00036                   D0040PA04X+020866Y+001376               S0      
317NNAME00036                   D0040PA00X+020866Y+008327               S0      
327NNAME00037                   D0040PA04X+020472Y+001376               S0      
317NNAME00037                   D0040PA00X+020472Y+009114               S0      
327PCIE1_RESET#                 D0040PA04X+019291Y+001376               S0      
317PCIE1_RESET#                 D0040PA00X+019291Y+008327               S0      
327PCIE_RSVD_B40                D0040PA04X+018898Y+001376               S0      
317PCIE_RSVD_B40                D0040PA00X+018898Y+009114               S0      
327GBE_SMBCLK_R                 D0040PA04X+017717Y+001376               S0      
317GBE_SMBCLK_R                 D0040PA00X+017717Y+008327               S0      
327GBE_SMDATA_R                 D0040PA04X+017323Y+001376               S0      
317GBE_SMDATA_R                 D0040PA00X+017323Y+009114               S0      
327NNAME00038                   D0040PA04X+016142Y+001376               S0      
317NNAME00038                   D0040PA00X+016142Y+008327               S0      
327NNAME00039                   D0040PA04X+015748Y+001571               S0      
317NNAME00039                   D0040PA00X+015748Y+009114               S0      
327NNAME00040                   D0040PA04X+014567Y+001376               S0      
317NNAME00040                   D0040PA00X+014567Y+008327               S0      
327NNAME00041                   D0040PA04X+014173Y+001376               S0      
317NNAME00041                   D0040PA00X+014173Y+009114               S0      
327NNAME00042                   D0040PA04X+012992Y+001376               S0      
317NNAME00042                   D0040PA00X+012992Y+008327               S0      
327NNAME00043                   D0040PA04X+012598Y+001376               S0      
317NNAME00043                   D0040PA00X+012598Y+009114               S0      
327NNAME00044                   D0040PA04X+011417Y+001376               S0      
317NNAME00044                   D0040PA00X+011417Y+008327               S0      
327NNAME00045                   D0040PA04X+011024Y+001376               S0      
317NNAME00045                   D0040PA00X+011024Y+009114               S0      
327NNAME00046                   D0040PA04X+009843Y+001376               S0      
317NNAME00046                   D0040PA00X+009843Y+008327               S0      
327NNAME00047                   D0040PA04X+009449Y+001376               S0      
317NNAME00047                   D0040PA00X+009449Y+009114               S0      
327NNAME00048                   D0040PA04X+008268Y+001376               S0      
317NNAME00048                   D0040PA00X+008268Y+008327               S0      
327NNAME00049                   D0040PA04X+007874Y+001376               S0      
317NNAME00049                   D0040PA00X+007874Y+009114               S0      
327NNAME00050                   D0040PA04X+006693Y+001376               S0      
317NNAME00050                   D0040PA00X+006693Y+008327               S0      
327NNAME00051                   D0040PA04X+006299Y+001376               S0      
317NNAME00051                   D0040PA00X+006299Y+009114               S0      
327NNAME00052                   D0040PA04X+005118Y+001376               S0      
317NNAME00052                   D0040PA00X+005118Y+008327               S0      
327NNAME00053                   D0040PA04X+004724Y+001376               S0      
317NNAME00053                   D0040PA00X+004724Y+009114               S0      
327NNAME00054                   D0040PA04X+003543Y+001376               S0      
317NNAME00054                   D0040PA00X+003543Y+008327               S0      
327NNAME00055                   D0040PA04X+003150Y+001376               S0      
317NNAME00055                   D0040PA00X+003150Y+009114               S0      
317$NONE$                       D0040PA00X+030453Y+007835               S0      
317$NONE$                       D0040PA00X+001654Y+007835               S0      
999
